FILE_TYPE = MULTI_PHYS_TABLE;
PART 'SCONN288_H44441004'
{====================================================================================================================================================================================================================}
:PACK_TYPE | MATERIAL | PART_NUMBER     = EnvComp  |   PART_NUMBER |  JEDEC_TYPE               | DESCRIPTION                            | CLASS | COMPONENT_TYPE | HEIGHT     | LPID     | SPEED_URL | Status |RPL| AML | Bus_Unit | Days ;
{===================================================================================================================================================================================================================}
'PIP'      | 'SCONN'  | 'H44441-004'(!) = ''       |  'H44441-004' | 'SCONN288_H44441004_PIP'  | '(USE SYM 1-4)CONN,CEDG,288P,DDR4,VT,0.85mm,SMT,BU' | 'IO'  | 'SMTCONN'      | '0.839 IN' |  '3551'  | 'http://speed.intel.com:8081/speed/module/pdm/item/pdm_item_detail_direct.asp?item_cde=H44441-004&item_rev=01&url_param=unused' | '' | '' | '' | '' | '' 
'PIP'      | 'EMPTY'  | 'H44441-004'(!) = ''       |  'H44441-004' | 'SCONN288_H44441004_PIP'  | '(USE SYM 1-4)CONN,CEDG,288P,DDR4,VT,0.85mm,SMT,BU' | 'IO'  | 'SMTCONN'      | '0.839 IN' |  '3551'  | 'http://speed.intel.com:8081/speed/module/pdm/item/pdm_item_detail_direct.asp?item_cde=H44441-004&item_rev=01&url_param=unused' | '' | '' | '' | '' | '' 
END_PART
END.
